(kicad_pcb
	(version 20260206)
	(generator "pcbnew")
	(generator_version "10.0")
	(general
		(thickness 1.6)
		(legacy_teardrops no)
	)
	(paper "A4")
	(title_block
		(title "Bryce Canyon_F.DPB_16315-1-OCP.brd")
		(comment 1 "Bryce Canyon / footprints 1002-1008 of 2223")
	)
	(layers
		(0 "F.Cu" signal "TOP")
		(4 "In1.Cu" signal "L2GND")
		(6 "In2.Cu" signal "L3")
		(8 "In3.Cu" signal "L4GND")
		(10 "In4.Cu" signal "L5")
		(12 "In5.Cu" signal "L6VCC")
		(14 "In6.Cu" signal "L7VCC")
		(16 "In7.Cu" signal "L8")
		(18 "In8.Cu" signal "L9GND")
		(20 "In9.Cu" signal "L10")
		(22 "In10.Cu" signal "L11GND")
		(2 "B.Cu" signal "BOTTOM")
		(9 "F.Adhes" user "F.Adhesive")
		(11 "B.Adhes" user "B.Adhesive")
		(13 "F.Paste" user "Package Geometry/Pastemask Top")
		(15 "B.Paste" user "Package Geometry/Pastemask Bottom")
		(5 "F.SilkS" user "Ref Des/Silkscreen Top")
		(7 "B.SilkS" user "Ref Des/Silkscreen Bottom")
		(1 "F.Mask" user "Board Geometry/Soldermask Top")
		(3 "B.Mask" user "Board Geometry/Soldermask Bottom")
		(17 "Dwgs.User" user "User.Drawings")
		(19 "Cmts.User" user "User.Comments")
		(21 "Eco1.User" user "User.Eco1")
		(23 "Eco2.User" user "User.Eco2")
		(25 "Edge.Cuts" user "Board Geometry/Outline")
		(27 "Margin" user)
		(31 "F.CrtYd" user "Package Geometry/Place Bound Top")
		(29 "B.CrtYd" user "Package Geometry/Place Bound Bottom")
		(35 "F.Fab" user "Ref Des/Assembly Top")
		(33 "B.Fab" user "Ref Des/Assembly Bottom")
	)
	(footprint ""
		(layer "F.Cu")
		(at 109.492796 -53.482494 -90)
		(property "Reference" "R766"
			(at 0 0 270)
			(layer "F.SilkS")
			(hide yes)
			(effects
				(font
					(size 1.27 1.27)
				)
			)
		)
		(property "Value" "300KR2F-GP"
			(at 0.064008 -3.993896 270)
			(unlocked yes)
			(layer "F.Fab")
			(hide yes)
			(effects
				(font
					(size 1.016 1.016)
					(thickness 0.1524)
				)
			)
		)
		(property "Device Type" "R402H16"
			(at 0.064008 -5.517896 270)
			(unlocked yes)
			(layer "F.Fab")
			(hide yes)
			(effects
				(font
					(size 1.016 1.016)
					(thickness 0.1524)
				)
			)
		)
		(duplicate_pad_numbers_are_jumpers no)
		(fp_line
			(start -0.508 -0.9398)
			(end -0.508 0.9398)
			(stroke
				(width 0.1524)
				(type default)
			)
			(layer "F.SilkS")
		)
		(fp_line
			(start 0.508 -0.9398)
			(end -0.508 -0.9398)
			(stroke
				(width 0.1524)
				(type default)
			)
			(layer "F.SilkS")
		)
		(fp_rect
			(start -0.508 0.9398)
			(end 0.508 -0.9398)
			(stroke
				(width 0)
				(type default)
			)
			(fill no)
			(layer "F.CrtYd")
		)
		(fp_rect
			(start -0.508 0.9398)
			(end 0.508 -0.9398)
			(stroke
				(width 0)
				(type default)
			)
			(fill no)
			(layer "F.Fab")
		)
		(pad "1" smd custom
			(at 0 -0.4445 270)
			(size 0.1397 0.1397)
			(layers "F.Cu" "F.Mask" "F.Paste")
			(net "SW_HDD_N27")
			(options
				(clearance outline)
				(anchor circle)
			)
			(primitives
				(gr_poly
					(pts
						(arc
							(start -0.1778 -0.2794)
							(mid -0.249642 -0.249642)
							(end -0.2794 -0.1778)
						)
						(arc
							(start -0.2794 0.1778)
							(mid -0.249642 0.249642)
							(end -0.1778 0.2794)
						)
						(arc
							(start 0.1778 0.2794)
							(mid 0.249642 0.249642)
							(end 0.2794 0.1778)
						)
						(arc
							(start 0.2794 -0.1778)
							(mid 0.249642 -0.249642)
							(end 0.1778 -0.2794)
						)
					)
					(width 0)
					(fill yes)
				)
			)
		)
		(pad "2" smd custom
			(at 0 0.4445 270)
			(size 0.1397 0.1397)
			(layers "F.Cu" "F.Mask" "F.Paste")
			(net "P12V_A")
			(options
				(clearance outline)
				(anchor circle)
			)
			(primitives
				(gr_poly
					(pts
						(arc
							(start -0.1778 -0.2794)
							(mid -0.249642 -0.249642)
							(end -0.2794 -0.1778)
						)
						(arc
							(start -0.2794 0.1778)
							(mid -0.249642 0.249642)
							(end -0.1778 0.2794)
						)
						(arc
							(start 0.1778 0.2794)
							(mid 0.249642 0.249642)
							(end 0.2794 0.1778)
						)
						(arc
							(start 0.2794 -0.1778)
							(mid 0.249642 -0.249642)
							(end 0.1778 -0.2794)
						)
					)
					(width 0)
					(fill yes)
				)
			)
		)
	)
	(footprint ""
		(layer "F.Cu")
		(at 32.04337 -252.151642 -90)
		(property "Reference" "R1213"
			(at 0 0 270)
			(layer "F.SilkS")
			(hide yes)
			(effects
				(font
					(size 1.27 1.27)
				)
			)
		)
		(property "Value" "15KR2F-GP"
			(at 0.064008 -3.993896 270)
			(unlocked yes)
			(layer "F.Fab")
			(hide yes)
			(effects
				(font
					(size 1.016 1.016)
					(thickness 0.1524)
				)
			)
		)
		(property "Device Type" "R402H16"
			(at 0.064008 -5.517896 270)
			(unlocked yes)
			(layer "F.Fab")
			(hide yes)
			(effects
				(font
					(size 1.016 1.016)
					(thickness 0.1524)
				)
			)
		)
		(duplicate_pad_numbers_are_jumpers no)
		(fp_line
			(start -0.508 -0.9398)
			(end -0.508 0.9398)
			(stroke
				(width 0.1524)
				(type default)
			)
			(layer "F.SilkS")
		)
		(fp_line
			(start 0.508 -0.9398)
			(end -0.508 -0.9398)
			(stroke
				(width 0.1524)
				(type default)
			)
			(layer "F.SilkS")
		)
		(fp_rect
			(start -0.508 0.9398)
			(end 0.508 -0.9398)
			(stroke
				(width 0)
				(type default)
			)
			(fill no)
			(layer "F.CrtYd")
		)
		(fp_rect
			(start -0.508 0.9398)
			(end 0.508 -0.9398)
			(stroke
				(width 0)
				(type default)
			)
			(fill no)
			(layer "F.Fab")
		)
		(pad "1" smd custom
			(at 0 -0.4445 270)
			(size 0.1397 0.1397)
			(layers "F.Cu" "F.Mask" "F.Paste")
			(net "P5V_A_1_PGOOD")
			(options
				(clearance outline)
				(anchor circle)
			)
			(primitives
				(gr_poly
					(pts
						(arc
							(start -0.1778 -0.2794)
							(mid -0.249642 -0.249642)
							(end -0.2794 -0.1778)
						)
						(arc
							(start -0.2794 0.1778)
							(mid -0.249642 0.249642)
							(end -0.1778 0.2794)
						)
						(arc
							(start 0.1778 0.2794)
							(mid 0.249642 0.249642)
							(end 0.2794 0.1778)
						)
						(arc
							(start 0.2794 -0.1778)
							(mid 0.249642 -0.249642)
							(end 0.1778 -0.2794)
						)
					)
					(width 0)
					(fill yes)
				)
			)
		)
		(pad "2" smd custom
			(at 0 0.4445 270)
			(size 0.1397 0.1397)
			(layers "F.Cu" "F.Mask" "F.Paste")
			(net "GND")
			(options
				(clearance outline)
				(anchor circle)
			)
			(primitives
				(gr_poly
					(pts
						(arc
							(start -0.1778 -0.2794)
							(mid -0.249642 -0.249642)
							(end -0.2794 -0.1778)
						)
						(arc
							(start -0.2794 0.1778)
							(mid -0.249642 0.249642)
							(end -0.1778 0.2794)
						)
						(arc
							(start 0.1778 0.2794)
							(mid 0.249642 0.249642)
							(end 0.2794 0.1778)
						)
						(arc
							(start 0.2794 -0.1778)
							(mid 0.249642 -0.249642)
							(end 0.1778 -0.2794)
						)
					)
					(width 0)
					(fill yes)
				)
			)
		)
	)
	(footprint ""
		(layer "F.Cu")
		(at 396.60195 -303.954942 180)
		(property "Reference" "C148"
			(at 0 0 180)
			(layer "F.SilkS")
			(hide yes)
			(effects
				(font
					(size 1.27 1.27)
				)
			)
		)
		(property "Value" "SC4D7U25V5KX-1-GP"
			(at -0.0762 -6.1214 180)
			(unlocked yes)
			(layer "F.Fab")
			(hide yes)
			(effects
				(font
					(size 1.016 1.016)
					(thickness 0.1524)
				)
			)
		)
		(property "Device Type" "C805H58"
			(at -0.0762 -8.1534 180)
			(unlocked yes)
			(layer "F.Fab")
			(hide yes)
			(effects
				(font
					(size 1.016 1.016)
					(thickness 0.1524)
				)
			)
		)
		(duplicate_pad_numbers_are_jumpers no)
		(fp_line
			(start 0.635 0)
			(end -0.635 0)
			(stroke
				(width 0.508)
				(type default)
			)
			(layer "F.SilkS")
		)
		(fp_rect
			(start -0.9652 1.778)
			(end 0.9652 -1.778)
			(stroke
				(width 0)
				(type default)
			)
			(fill no)
			(layer "F.CrtYd")
		)
		(fp_poly
			(pts
				(xy -0.9652 -1.778) (xy 0.9652 -1.778) (xy 0.9652 1.778) (xy -0.9652 1.778)
			)
			(stroke
				(width 0)
				(type default)
			)
			(fill no)
			(layer "F.Fab")
		)
		(pad "1" smd rect
			(at 0 -0.9652 180)
			(size 1.397 1.143)
			(layers "F.Cu" "F.Mask" "F.Paste")
			(net "P12V_HDD8")
		)
		(pad "2" smd rect
			(at 0 0.9652 180)
			(size 1.397 1.143)
			(layers "F.Cu" "F.Mask" "F.Paste")
			(net "GND")
		)
	)
	(footprint ""
		(layer "F.Cu")
		(at 479.384614 -44.219368 -90)
		(property "Reference" "C493"
			(at 0 0 270)
			(layer "F.SilkS")
			(hide yes)
			(effects
				(font
					(size 1.27 1.27)
				)
			)
		)
		(property "Value" "SCD01U16V1KX-GP"
			(at -2.8321 -1.7399 270)
			(unlocked yes)
			(layer "F.Fab")
			(hide yes)
			(effects
				(font
					(size 1.016 1.016)
					(thickness 0.1524)
				)
			)
		)
		(property "Device Type" "C0201H13"
			(at -2.8321 -3.2639 270)
			(unlocked yes)
			(layer "F.Fab")
			(hide yes)
			(effects
				(font
					(size 1.016 1.016)
					(thickness 0.1524)
				)
			)
		)
		(duplicate_pad_numbers_are_jumpers no)
		(fp_rect
			(start -0.2794 0.6477)
			(end 0.2794 -0.6477)
			(stroke
				(width 0)
				(type default)
			)
			(fill no)
			(layer "F.CrtYd")
		)
		(fp_rect
			(start -0.2794 0.6477)
			(end 0.2794 -0.6477)
			(stroke
				(width 0)
				(type default)
			)
			(fill no)
			(layer "F.Fab")
		)
		(pad "1" smd custom
			(at 0 -0.2794 270)
			(size 0.0762 0.0762)
			(layers "F.Cu" "F.Mask" "F.Paste")
			(net "SAS_HDD_RX_N35")
			(options
				(clearance outline)
				(anchor circle)
			)
			(primitives
				(gr_poly
					(pts
						(arc
							(start 0.1524 -0.127)
							(mid 0.137521 -0.162921)
							(end 0.1016 -0.1778)
						)
						(arc
							(start -0.1016 -0.1778)
							(mid -0.137521 -0.162921)
							(end -0.1524 -0.127)
						)
						(arc
							(start -0.1524 0.127)
							(mid -0.137521 0.162921)
							(end -0.1016 0.1778)
						)
						(arc
							(start 0.1016 0.1778)
							(mid 0.137521 0.162921)
							(end 0.1524 0.127)
						)
					)
					(width 0)
					(fill yes)
				)
			)
		)
		(pad "2" smd custom
			(at 0 0.2794 270)
			(size 0.0762 0.0762)
			(layers "F.Cu" "F.Mask" "F.Paste")
			(net "PHY_SCC_A_TO_DRV_A_35_DN")
			(options
				(clearance outline)
				(anchor circle)
			)
			(primitives
				(gr_poly
					(pts
						(arc
							(start 0.1524 -0.127)
							(mid 0.137521 -0.162921)
							(end 0.1016 -0.1778)
						)
						(arc
							(start -0.1016 -0.1778)
							(mid -0.137521 -0.162921)
							(end -0.1524 -0.127)
						)
						(arc
							(start -0.1524 0.127)
							(mid -0.137521 0.162921)
							(end -0.1016 0.1778)
						)
						(arc
							(start 0.1016 0.1778)
							(mid 0.137521 0.162921)
							(end 0.1524 0.127)
						)
					)
					(width 0)
					(fill yes)
				)
			)
		)
	)
	(footprint ""
		(layer "F.Cu")
		(at 149.196298 -48.554894 90)
		(property "Reference" "R787"
			(at 0 0 90)
			(layer "F.SilkS")
			(hide yes)
			(effects
				(font
					(size 1.27 1.27)
				)
			)
		)
		(property "Value" "4K7R2J-2-GP"
			(at 0.064008 -3.993896 90)
			(unlocked yes)
			(layer "F.Fab")
			(hide yes)
			(effects
				(font
					(size 1.016 1.016)
					(thickness 0.1524)
				)
			)
		)
		(property "Device Type" "R402H16"
			(at 0.064008 -5.517896 90)
			(unlocked yes)
			(layer "F.Fab")
			(hide yes)
			(effects
				(font
					(size 1.016 1.016)
					(thickness 0.1524)
				)
			)
		)
		(duplicate_pad_numbers_are_jumpers no)
		(fp_line
			(start 0.508 -0.9398)
			(end -0.508 -0.9398)
			(stroke
				(width 0.1524)
				(type default)
			)
			(layer "F.SilkS")
		)
		(fp_line
			(start -0.508 -0.9398)
			(end -0.508 0.9398)
			(stroke
				(width 0.1524)
				(type default)
			)
			(layer "F.SilkS")
		)
		(fp_rect
			(start -0.508 0.9398)
			(end 0.508 -0.9398)
			(stroke
				(width 0)
				(type default)
			)
			(fill no)
			(layer "F.CrtYd")
		)
		(fp_rect
			(start -0.508 0.9398)
			(end 0.508 -0.9398)
			(stroke
				(width 0)
				(type default)
			)
			(fill no)
			(layer "F.Fab")
		)
		(pad "1" smd custom
			(at 0 -0.4445 90)
			(size 0.1397 0.1397)
			(layers "F.Cu" "F.Mask" "F.Paste")
			(net "SW_PWR_R_HDD28")
			(options
				(clearance outline)
				(anchor circle)
			)
			(primitives
				(gr_poly
					(pts
						(arc
							(start -0.1778 -0.2794)
							(mid -0.249642 -0.249642)
							(end -0.2794 -0.1778)
						)
						(arc
							(start -0.2794 0.1778)
							(mid -0.249642 0.249642)
							(end -0.1778 0.2794)
						)
						(arc
							(start 0.1778 0.2794)
							(mid 0.249642 0.249642)
							(end 0.2794 0.1778)
						)
						(arc
							(start 0.2794 -0.1778)
							(mid 0.249642 -0.249642)
							(end 0.1778 -0.2794)
						)
					)
					(width 0)
					(fill yes)
				)
			)
		)
		(pad "2" smd custom
			(at 0 0.4445 90)
			(size 0.1397 0.1397)
			(layers "F.Cu" "F.Mask" "F.Paste")
			(net "GND")
			(options
				(clearance outline)
				(anchor circle)
			)
			(primitives
				(gr_poly
					(pts
						(arc
							(start -0.1778 -0.2794)
							(mid -0.249642 -0.249642)
							(end -0.2794 -0.1778)
						)
						(arc
							(start -0.2794 0.1778)
							(mid -0.249642 0.249642)
							(end -0.1778 0.2794)
						)
						(arc
							(start 0.1778 0.2794)
							(mid 0.249642 0.249642)
							(end 0.2794 0.1778)
						)
						(arc
							(start 0.2794 -0.1778)
							(mid 0.249642 -0.249642)
							(end 0.1778 -0.2794)
						)
					)
					(width 0)
					(fill yes)
				)
			)
		)
	)
	(footprint ""
		(layer "F.Cu")
		(at 363.3978 -137.1854 90)
		(property "Reference" "R1073"
			(at 0 0 90)
			(layer "F.SilkS")
			(hide yes)
			(effects
				(font
					(size 1.27 1.27)
				)
			)
		)
		(property "Value" "10R2F-L-GP"
			(at 0.064008 -3.993896 90)
			(unlocked yes)
			(layer "F.Fab")
			(hide yes)
			(effects
				(font
					(size 1.016 1.016)
					(thickness 0.1524)
				)
			)
		)
		(property "Device Type" "R402H14"
			(at 0.064008 -5.517896 90)
			(unlocked yes)
			(layer "F.Fab")
			(hide yes)
			(effects
				(font
					(size 1.016 1.016)
					(thickness 0.1524)
				)
			)
		)
		(duplicate_pad_numbers_are_jumpers no)
		(fp_line
			(start 0.508 -0.9398)
			(end -0.508 -0.9398)
			(stroke
				(width 0.1524)
				(type default)
			)
			(layer "F.SilkS")
		)
		(fp_line
			(start -0.508 -0.9398)
			(end -0.508 0.9398)
			(stroke
				(width 0.1524)
				(type default)
			)
			(layer "F.SilkS")
		)
		(fp_rect
			(start -0.508 0.9398)
			(end 0.508 -0.9398)
			(stroke
				(width 0)
				(type default)
			)
			(fill no)
			(layer "F.CrtYd")
		)
		(fp_rect
			(start -0.508 0.9398)
			(end 0.508 -0.9398)
			(stroke
				(width 0)
				(type default)
			)
			(fill no)
			(layer "F.Fab")
		)
		(pad "1" smd custom
			(at 0 -0.4445 90)
			(size 0.1397 0.1397)
			(layers "F.Cu" "F.Mask" "F.Paste")
			(net "P12V_B")
			(options
				(clearance outline)
				(anchor circle)
			)
			(primitives
				(gr_poly
					(pts
						(arc
							(start -0.1778 -0.2794)
							(mid -0.249642 -0.249642)
							(end -0.2794 -0.1778)
						)
						(arc
							(start -0.2794 0.1778)
							(mid -0.249642 0.249642)
							(end -0.1778 0.2794)
						)
						(arc
							(start 0.1778 0.2794)
							(mid 0.249642 0.249642)
							(end 0.2794 0.1778)
						)
						(arc
							(start 0.2794 -0.1778)
							(mid 0.249642 -0.249642)
							(end 0.1778 -0.2794)
						)
					)
					(width 0)
					(fill yes)
				)
			)
		)
		(pad "2" smd custom
			(at 0 0.4445 90)
			(size 0.1397 0.1397)
			(layers "F.Cu" "F.Mask" "F.Paste")
			(net "MB1_P12V_HS")
			(options
				(clearance outline)
				(anchor circle)
			)
			(primitives
				(gr_poly
					(pts
						(arc
							(start -0.1778 -0.2794)
							(mid -0.249642 -0.249642)
							(end -0.2794 -0.1778)
						)
						(arc
							(start -0.2794 0.1778)
							(mid -0.249642 0.249642)
							(end -0.1778 0.2794)
						)
						(arc
							(start 0.1778 0.2794)
							(mid 0.249642 0.249642)
							(end 0.2794 0.1778)
						)
						(arc
							(start 0.2794 -0.1778)
							(mid 0.249642 -0.249642)
							(end 0.1778 -0.2794)
						)
					)
					(width 0)
					(fill yes)
				)
			)
		)
	)
	(footprint ""
		(layer "F.Cu")
		(at 138.007852 -140.962126 180)
		(property "Reference" "C27"
			(at 0 0 180)
			(layer "F.SilkS")
			(hide yes)
			(effects
				(font
					(size 1.27 1.27)
				)
			)
		)
		(property "Value" "SCD1U16V2KX-3GP"
			(at 1.1811 -2.7051 180)
			(unlocked yes)
			(layer "F.Fab")
			(hide yes)
			(effects
				(font
					(size 1.016 1.016)
					(thickness 0.1524)
				)
			)
		)
		(property "Device Type" "C402H22"
			(at 1.1811 -4.2291 180)
			(unlocked yes)
			(layer "F.Fab")
			(hide yes)
			(effects
				(font
					(size 1.016 1.016)
					(thickness 0.1524)
				)
			)
		)
		(duplicate_pad_numbers_are_jumpers no)
		(fp_rect
			(start -0.4318 0.9525)
			(end 0.4318 -0.9525)
			(stroke
				(width 0)
				(type default)
			)
			(fill no)
			(layer "F.CrtYd")
		)
		(fp_rect
			(start -0.4318 0.9525)
			(end 0.4318 -0.9525)
			(stroke
				(width 0)
				(type default)
			)
			(fill no)
			(layer "F.Fab")
		)
		(pad "1" smd custom
			(at 0 -0.4445 180)
			(size 0.1524 0.1524)
			(layers "F.Cu" "F.Mask" "F.Paste")
			(net "P3V3_A_BIAS")
			(options
				(clearance outline)
				(anchor circle)
			)
			(primitives
				(gr_poly
					(pts
						(arc
							(start 0.3048 -0.2032)
							(mid 0.275042 -0.275042)
							(end 0.2032 -0.3048)
						)
						(arc
							(start -0.2032 -0.3048)
							(mid -0.275042 -0.275042)
							(end -0.3048 -0.2032)
						)
						(arc
							(start -0.3048 0.2032)
							(mid -0.275042 0.275042)
							(end -0.2032 0.3048)
						)
						(arc
							(start 0.2032 0.3048)
							(mid 0.275042 0.275042)
							(end 0.3048 0.2032)
						)
					)
					(width 0)
					(fill yes)
				)
			)
		)
		(pad "2" smd custom
			(at 0 0.4445 180)
			(size 0.1524 0.1524)
			(layers "F.Cu" "F.Mask" "F.Paste")
			(net "GND")
			(options
				(clearance outline)
				(anchor circle)
			)
			(primitives
				(gr_poly
					(pts
						(arc
							(start 0.3048 -0.2032)
							(mid 0.275042 -0.275042)
							(end 0.2032 -0.3048)
						)
						(arc
							(start -0.2032 -0.3048)
							(mid -0.275042 -0.275042)
							(end -0.3048 -0.2032)
						)
						(arc
							(start -0.3048 0.2032)
							(mid -0.275042 0.275042)
							(end -0.2032 0.3048)
						)
						(arc
							(start 0.2032 0.3048)
							(mid 0.275042 0.275042)
							(end 0.3048 0.2032)
						)
					)
					(width 0)
					(fill yes)
				)
			)
		)
	)
)
